(kicad_pcb
	(version 20260206)
	(generator "pcbnew")
	(generator_version "10.0")
	(general
		(thickness 1.6)
		(legacy_teardrops no)
	)
	(paper "A4")
	(title_block
		(title "Wiwynn_Tioga_Pass_MB.brd")
		(comment 1 "Tioga Pass / footprint 990 of 4770 (J4B1), pads 1-123 of 291")
	)
	(layers
		(0 "F.Cu" signal "TOP")
		(4 "In1.Cu" signal "L2GND")
		(6 "In2.Cu" signal "L3")
		(8 "In3.Cu" signal "L4GND")
		(10 "In4.Cu" signal "L5")
		(12 "In5.Cu" signal "L6GND")
		(14 "In6.Cu" signal "L7VCC")
		(16 "In7.Cu" signal "L8VCC")
		(18 "In8.Cu" signal "L9GND")
		(20 "In9.Cu" signal "L10")
		(22 "In10.Cu" signal "L11GND")
		(24 "In11.Cu" signal "L12")
		(26 "In12.Cu" signal "L13GND")
		(2 "B.Cu" signal "BOTTOM")
		(9 "F.Adhes" user "F.Adhesive")
		(11 "B.Adhes" user "B.Adhesive")
		(13 "F.Paste" user "Package Geometry/Pastemask Top")
		(15 "B.Paste" user "Package Geometry/Pastemask Bottom")
		(5 "F.SilkS" user "Ref Des/Silkscreen Top")
		(7 "B.SilkS" user "Ref Des/Silkscreen Bottom")
		(1 "F.Mask" user "Board Geometry/Soldermask Top")
		(3 "B.Mask" user "Board Geometry/Soldermask Bottom")
		(17 "Dwgs.User" user "User.Drawings")
		(19 "Cmts.User" user "User.Comments")
		(21 "Eco1.User" user "User.Eco1")
		(23 "Eco2.User" user "User.Eco2")
		(25 "Edge.Cuts" user "Board Geometry/Outline")
		(27 "Margin" user)
		(31 "F.CrtYd" user "Package Geometry/Place Bound Top")
		(29 "B.CrtYd" user "Package Geometry/Place Bound Bottom")
		(35 "F.Fab" user "Ref Des/Assembly Top")
		(33 "B.Fab" user "Ref Des/Assembly Bottom")
	)
	(footprint ""
		(layer "F.Cu")
		(at 194.700398 -133.0706 90)
		(property "Reference" "J4B1"
			(at -5.087112 42.28211 0)
			(unlocked yes)
			(layer "F.SilkS")
			(effects
				(font
					(size 0.7874 0.5842)
					(thickness 0.1524)
				)
				(justify left)
			)
		)
		(property "Value" ""
			(at 0 0 90)
			(layer "F.Fab")
			(effects
				(font
					(size 1.27 1.27)
				)
			)
		)
		(duplicate_pad_numbers_are_jumpers no)
		(pad "" thru_hole circle
			(at 2.29997 -5.649976 90)
			(size 2.8194 2.8194)
			(drill 2.4384)
			(layers "*.Cu" "*.Mask")
			(remove_unused_layers no)
			(clearance 0.127)
			(thermal_gap 0.127)
		)
		(pad "" thru_hole oval
			(at 2.29997 68.90004 90)
			(size 2.8194 1.5748)
			(drill oval 2.4384 1.1938)
			(layers "*.Cu" "*.Mask")
			(remove_unused_layers no)
			(clearance 0.127)
			(thermal_gap 0.127)
		)
		(pad "" thru_hole circle
			(at 2.29997 132.299964 90)
			(size 2.8194 2.8194)
			(drill 2.4384)
			(layers "*.Cu" "*.Mask")
			(remove_unused_layers no)
			(clearance 0.127)
			(thermal_gap 0.127)
		)
		(pad "1" smd rect
			(at 0 0 90)
			(size 1.8034 0.508)
			(layers "F.Cu" "F.Mask" "F.Paste")
			(net "P12V_NVDIMM_DEF")
		)
		(pad "2" smd rect
			(at 0 0.849884 90)
			(size 1.8034 0.508)
			(layers "F.Cu" "F.Mask" "F.Paste")
			(net "GND")
		)
		(pad "3" smd rect
			(at 0 1.700022 90)
			(size 1.8034 0.508)
			(layers "F.Cu" "F.Mask" "F.Paste")
			(net "M_D_DQ<5>")
		)
		(pad "4" smd rect
			(at 0 2.549906 90)
			(size 1.8034 0.508)
			(layers "F.Cu" "F.Mask" "F.Paste")
			(net "GND")
		)
		(pad "5" smd rect
			(at 0 3.400044 90)
			(size 1.8034 0.508)
			(layers "F.Cu" "F.Mask" "F.Paste")
			(net "M_D_DQ<1>")
		)
		(pad "6" smd rect
			(at 0 4.249928 90)
			(size 1.8034 0.508)
			(layers "F.Cu" "F.Mask" "F.Paste")
			(net "GND")
		)
		(pad "7" smd rect
			(at 0 5.100066 90)
			(size 1.8034 0.508)
			(layers "F.Cu" "F.Mask" "F.Paste")
			(net "M_D_DQS_DP<9>")
		)
		(pad "8" smd rect
			(at 0 5.94995 90)
			(size 1.8034 0.508)
			(layers "F.Cu" "F.Mask" "F.Paste")
			(net "M_D_DQS_DN<9>")
		)
		(pad "9" smd rect
			(at 0 6.800088 90)
			(size 1.8034 0.508)
			(layers "F.Cu" "F.Mask" "F.Paste")
			(net "GND")
		)
		(pad "10" smd rect
			(at 0 7.649972 90)
			(size 1.8034 0.508)
			(layers "F.Cu" "F.Mask" "F.Paste")
			(net "M_D_DQ<7>")
		)
		(pad "11" smd rect
			(at 0 8.50011 90)
			(size 1.8034 0.508)
			(layers "F.Cu" "F.Mask" "F.Paste")
			(net "GND")
		)
		(pad "12" smd rect
			(at 0 9.349994 90)
			(size 1.8034 0.508)
			(layers "F.Cu" "F.Mask" "F.Paste")
			(net "M_D_DQ<3>")
		)
		(pad "13" smd rect
			(at 0 10.199878 90)
			(size 1.8034 0.508)
			(layers "F.Cu" "F.Mask" "F.Paste")
			(net "GND")
		)
		(pad "14" smd rect
			(at 0 11.050016 90)
			(size 1.8034 0.508)
			(layers "F.Cu" "F.Mask" "F.Paste")
			(net "M_D_DQ<13>")
		)
		(pad "15" smd rect
			(at 0 11.8999 90)
			(size 1.8034 0.508)
			(layers "F.Cu" "F.Mask" "F.Paste")
			(net "GND")
		)
		(pad "16" smd rect
			(at 0 12.750038 90)
			(size 1.8034 0.508)
			(layers "F.Cu" "F.Mask" "F.Paste")
			(net "M_D_DQ<9>")
		)
		(pad "17" smd rect
			(at 0 13.599922 90)
			(size 1.8034 0.508)
			(layers "F.Cu" "F.Mask" "F.Paste")
			(net "GND")
		)
		(pad "18" smd rect
			(at 0 14.45006 90)
			(size 1.8034 0.508)
			(layers "F.Cu" "F.Mask" "F.Paste")
			(net "M_D_DQS_DP<10>")
		)
		(pad "19" smd rect
			(at 0 15.299944 90)
			(size 1.8034 0.508)
			(layers "F.Cu" "F.Mask" "F.Paste")
			(net "M_D_DQS_DN<10>")
		)
		(pad "20" smd rect
			(at 0 16.150082 90)
			(size 1.8034 0.508)
			(layers "F.Cu" "F.Mask" "F.Paste")
			(net "GND")
		)
		(pad "21" smd rect
			(at 0 16.999966 90)
			(size 1.8034 0.508)
			(layers "F.Cu" "F.Mask" "F.Paste")
			(net "M_D_DQ<15>")
		)
		(pad "22" smd rect
			(at 0 17.850104 90)
			(size 1.8034 0.508)
			(layers "F.Cu" "F.Mask" "F.Paste")
			(net "GND")
		)
		(pad "23" smd rect
			(at 0 18.699988 90)
			(size 1.8034 0.508)
			(layers "F.Cu" "F.Mask" "F.Paste")
			(net "M_D_DQ<11>")
		)
		(pad "24" smd rect
			(at 0 19.550126 90)
			(size 1.8034 0.508)
			(layers "F.Cu" "F.Mask" "F.Paste")
			(net "GND")
		)
		(pad "25" smd rect
			(at 0 20.40001 90)
			(size 1.8034 0.508)
			(layers "F.Cu" "F.Mask" "F.Paste")
			(net "M_D_DQ<21>")
		)
		(pad "26" smd rect
			(at 0 21.249894 90)
			(size 1.8034 0.508)
			(layers "F.Cu" "F.Mask" "F.Paste")
			(net "GND")
		)
		(pad "27" smd rect
			(at 0 22.100032 90)
			(size 1.8034 0.508)
			(layers "F.Cu" "F.Mask" "F.Paste")
			(net "M_D_DQ<17>")
		)
		(pad "28" smd rect
			(at 0 22.949916 90)
			(size 1.8034 0.508)
			(layers "F.Cu" "F.Mask" "F.Paste")
			(net "GND")
		)
		(pad "29" smd rect
			(at 0 23.800054 90)
			(size 1.8034 0.508)
			(layers "F.Cu" "F.Mask" "F.Paste")
			(net "M_D_DQS_DP<11>")
		)
		(pad "30" smd rect
			(at 0 24.649938 90)
			(size 1.8034 0.508)
			(layers "F.Cu" "F.Mask" "F.Paste")
			(net "M_D_DQS_DN<11>")
		)
		(pad "31" smd rect
			(at 0 25.500076 90)
			(size 1.8034 0.508)
			(layers "F.Cu" "F.Mask" "F.Paste")
			(net "GND")
		)
		(pad "32" smd rect
			(at 0 26.34996 90)
			(size 1.8034 0.508)
			(layers "F.Cu" "F.Mask" "F.Paste")
			(net "M_D_DQ<23>")
		)
		(pad "33" smd rect
			(at 0 27.200098 90)
			(size 1.8034 0.508)
			(layers "F.Cu" "F.Mask" "F.Paste")
			(net "GND")
		)
		(pad "34" smd rect
			(at 0 28.049982 90)
			(size 1.8034 0.508)
			(layers "F.Cu" "F.Mask" "F.Paste")
			(net "M_D_DQ<19>")
		)
		(pad "35" smd rect
			(at 0 28.90012 90)
			(size 1.8034 0.508)
			(layers "F.Cu" "F.Mask" "F.Paste")
			(net "GND")
		)
		(pad "36" smd rect
			(at 0 29.750004 90)
			(size 1.8034 0.508)
			(layers "F.Cu" "F.Mask" "F.Paste")
			(net "M_D_DQ<29>")
		)
		(pad "37" smd rect
			(at 0 30.599888 90)
			(size 1.8034 0.508)
			(layers "F.Cu" "F.Mask" "F.Paste")
			(net "GND")
		)
		(pad "38" smd rect
			(at 0 31.450026 90)
			(size 1.8034 0.508)
			(layers "F.Cu" "F.Mask" "F.Paste")
			(net "M_D_DQ<25>")
		)
		(pad "39" smd rect
			(at 0 32.29991 90)
			(size 1.8034 0.508)
			(layers "F.Cu" "F.Mask" "F.Paste")
			(net "GND")
		)
		(pad "40" smd rect
			(at 0 33.150048 90)
			(size 1.8034 0.508)
			(layers "F.Cu" "F.Mask" "F.Paste")
			(net "M_D_DQS_DP<12>")
		)
		(pad "41" smd rect
			(at 0 33.999932 90)
			(size 1.8034 0.508)
			(layers "F.Cu" "F.Mask" "F.Paste")
			(net "M_D_DQS_DN<12>")
		)
		(pad "42" smd rect
			(at 0 34.85007 90)
			(size 1.8034 0.508)
			(layers "F.Cu" "F.Mask" "F.Paste")
			(net "GND")
		)
		(pad "43" smd rect
			(at 0 35.699954 90)
			(size 1.8034 0.508)
			(layers "F.Cu" "F.Mask" "F.Paste")
			(net "M_D_DQ<31>")
		)
		(pad "44" smd rect
			(at 0 36.550092 90)
			(size 1.8034 0.508)
			(layers "F.Cu" "F.Mask" "F.Paste")
			(net "GND")
		)
		(pad "45" smd rect
			(at 0 37.399976 90)
			(size 1.8034 0.508)
			(layers "F.Cu" "F.Mask" "F.Paste")
			(net "M_D_DQ<27>")
		)
		(pad "46" smd rect
			(at 0 38.250114 90)
			(size 1.8034 0.508)
			(layers "F.Cu" "F.Mask" "F.Paste")
			(net "GND")
		)
		(pad "47" smd rect
			(at 0 39.099998 90)
			(size 1.8034 0.508)
			(layers "F.Cu" "F.Mask" "F.Paste")
			(net "M_D_ECC<5>")
		)
		(pad "48" smd rect
			(at 0 39.949882 90)
			(size 1.8034 0.508)
			(layers "F.Cu" "F.Mask" "F.Paste")
			(net "GND")
		)
		(pad "49" smd rect
			(at 0 40.80002 90)
			(size 1.8034 0.508)
			(layers "F.Cu" "F.Mask" "F.Paste")
			(net "M_D_ECC<1>")
		)
		(pad "50" smd rect
			(at 0 41.649904 90)
			(size 1.8034 0.508)
			(layers "F.Cu" "F.Mask" "F.Paste")
			(net "GND")
		)
		(pad "51" smd rect
			(at 0 42.500042 90)
			(size 1.8034 0.508)
			(layers "F.Cu" "F.Mask" "F.Paste")
			(net "M_D_DQS_DP<17>")
		)
		(pad "52" smd rect
			(at 0 43.349926 90)
			(size 1.8034 0.508)
			(layers "F.Cu" "F.Mask" "F.Paste")
			(net "M_D_DQS_DN<17>")
		)
		(pad "53" smd rect
			(at 0 44.200064 90)
			(size 1.8034 0.508)
			(layers "F.Cu" "F.Mask" "F.Paste")
			(net "GND")
		)
		(pad "54" smd rect
			(at 0 45.049948 90)
			(size 1.8034 0.508)
			(layers "F.Cu" "F.Mask" "F.Paste")
			(net "M_D_ECC<7>")
		)
		(pad "55" smd rect
			(at 0 45.900086 90)
			(size 1.8034 0.508)
			(layers "F.Cu" "F.Mask" "F.Paste")
			(net "GND")
		)
		(pad "56" smd rect
			(at 0 46.74997 90)
			(size 1.8034 0.508)
			(layers "F.Cu" "F.Mask" "F.Paste")
			(net "M_D_ECC<3>")
		)
		(pad "57" smd rect
			(at 0 47.600108 90)
			(size 1.8034 0.508)
			(layers "F.Cu" "F.Mask" "F.Paste")
			(net "GND")
		)
		(pad "58" smd rect
			(at 0 48.449992 90)
			(size 1.8034 0.508)
			(layers "F.Cu" "F.Mask" "F.Paste")
			(net "M_DEF_RST_N")
		)
		(pad "59" smd rect
			(at 0 49.299876 90)
			(size 1.8034 0.508)
			(layers "F.Cu" "F.Mask" "F.Paste")
			(net "PVDDQ_DEF")
		)
		(pad "60" smd rect
			(at 0 50.150014 90)
			(size 1.8034 0.508)
			(layers "F.Cu" "F.Mask" "F.Paste")
			(net "M_D_CKE<0>")
		)
		(pad "61" smd rect
			(at 0 50.999898 90)
			(size 1.8034 0.508)
			(layers "F.Cu" "F.Mask" "F.Paste")
			(net "PVDDQ_DEF")
		)
		(pad "62" smd rect
			(at 0 51.850036 90)
			(size 1.8034 0.508)
			(layers "F.Cu" "F.Mask" "F.Paste")
			(net "M_D_ACT_N")
		)
		(pad "63" smd rect
			(at 0 52.69992 90)
			(size 1.8034 0.508)
			(layers "F.Cu" "F.Mask" "F.Paste")
			(net "M_D_BG<0>")
		)
		(pad "64" smd rect
			(at 0 53.550058 90)
			(size 1.8034 0.508)
			(layers "F.Cu" "F.Mask" "F.Paste")
			(net "PVDDQ_DEF")
		)
		(pad "65" smd rect
			(at 0 54.399942 90)
			(size 1.8034 0.508)
			(layers "F.Cu" "F.Mask" "F.Paste")
			(net "M_D_MA<12>")
		)
		(pad "66" smd rect
			(at 0 55.25008 90)
			(size 1.8034 0.508)
			(layers "F.Cu" "F.Mask" "F.Paste")
			(net "M_D_MA<9>")
		)
		(pad "67" smd rect
			(at 0 56.099964 90)
			(size 1.8034 0.508)
			(layers "F.Cu" "F.Mask" "F.Paste")
			(net "PVDDQ_DEF")
		)
		(pad "68" smd rect
			(at 0 56.950102 90)
			(size 1.8034 0.508)
			(layers "F.Cu" "F.Mask" "F.Paste")
			(net "M_D_MA<8>")
		)
		(pad "69" smd rect
			(at 0 57.799986 90)
			(size 1.8034 0.508)
			(layers "F.Cu" "F.Mask" "F.Paste")
			(net "M_D_MA<6>")
		)
		(pad "70" smd rect
			(at 0 58.650124 90)
			(size 1.8034 0.508)
			(layers "F.Cu" "F.Mask" "F.Paste")
			(net "PVDDQ_DEF")
		)
		(pad "71" smd rect
			(at 0 59.500008 90)
			(size 1.8034 0.508)
			(layers "F.Cu" "F.Mask" "F.Paste")
			(net "M_D_MA<3>")
		)
		(pad "72" smd rect
			(at 0 60.349892 90)
			(size 1.8034 0.508)
			(layers "F.Cu" "F.Mask" "F.Paste")
			(net "M_D_MA<1>")
		)
		(pad "73" smd rect
			(at 0 61.20003 90)
			(size 1.8034 0.508)
			(layers "F.Cu" "F.Mask" "F.Paste")
			(net "PVDDQ_DEF")
		)
		(pad "74" smd rect
			(at 0 62.049914 90)
			(size 1.8034 0.508)
			(layers "F.Cu" "F.Mask" "F.Paste")
			(net "M_D_CLK_DP<0>")
		)
		(pad "75" smd rect
			(at 0 62.900052 90)
			(size 1.8034 0.508)
			(layers "F.Cu" "F.Mask" "F.Paste")
			(net "M_D_CLK_DN<0>")
		)
		(pad "76" smd rect
			(at 0 63.749936 90)
			(size 1.8034 0.508)
			(layers "F.Cu" "F.Mask" "F.Paste")
			(net "PVDDQ_DEF")
		)
		(pad "77" smd rect
			(at 0 64.600074 90)
			(size 1.8034 0.508)
			(layers "F.Cu" "F.Mask" "F.Paste")
			(net "PVTT_DEF")
		)
		(pad "78" smd rect
			(at 0 70.550024 90)
			(size 1.8034 0.508)
			(layers "F.Cu" "F.Mask" "F.Paste")
			(net "FM_DIMM_EVENT_COD_N")
		)
		(pad "79" smd rect
			(at 0 71.399908 90)
			(size 1.8034 0.508)
			(layers "F.Cu" "F.Mask" "F.Paste")
			(net "M_D_MA<0>")
		)
		(pad "80" smd rect
			(at 0 72.250046 90)
			(size 1.8034 0.508)
			(layers "F.Cu" "F.Mask" "F.Paste")
			(net "PVDDQ_DEF")
		)
		(pad "81" smd rect
			(at 0 73.09993 90)
			(size 1.8034 0.508)
			(layers "F.Cu" "F.Mask" "F.Paste")
			(net "M_D_BA<0>")
		)
		(pad "82" smd rect
			(at 0 73.950068 90)
			(size 1.8034 0.508)
			(layers "F.Cu" "F.Mask" "F.Paste")
			(net "M_D_MA<16>")
		)
		(pad "83" smd rect
			(at 0 74.799952 90)
			(size 1.8034 0.508)
			(layers "F.Cu" "F.Mask" "F.Paste")
			(net "PVDDQ_DEF")
		)
		(pad "84" smd rect
			(at 0 75.65009 90)
			(size 1.8034 0.508)
			(layers "F.Cu" "F.Mask" "F.Paste")
			(net "M_D_CS_N<0>")
		)
		(pad "85" smd rect
			(at 0 76.499974 90)
			(size 1.8034 0.508)
			(layers "F.Cu" "F.Mask" "F.Paste")
			(net "PVDDQ_DEF")
		)
		(pad "86" smd rect
			(at 0 77.350112 90)
			(size 1.8034 0.508)
			(layers "F.Cu" "F.Mask" "F.Paste")
			(net "M_D_MA<15>")
		)
		(pad "87" smd rect
			(at 0 78.199996 90)
			(size 1.8034 0.508)
			(layers "F.Cu" "F.Mask" "F.Paste")
			(net "M_D_ODT<0>")
		)
		(pad "88" smd rect
			(at 0 79.04988 90)
			(size 1.8034 0.508)
			(layers "F.Cu" "F.Mask" "F.Paste")
			(net "PVDDQ_DEF")
		)
		(pad "89" smd rect
			(at 0 79.900018 90)
			(size 1.8034 0.508)
			(layers "F.Cu" "F.Mask" "F.Paste")
			(net "M_D_CS_N<1>")
		)
		(pad "90" smd rect
			(at 0 80.749902 90)
			(size 1.8034 0.508)
			(layers "F.Cu" "F.Mask" "F.Paste")
			(net "PVDDQ_DEF")
		)
		(pad "91" smd rect
			(at 0 81.60004 90)
			(size 1.8034 0.508)
			(layers "F.Cu" "F.Mask" "F.Paste")
			(net "M_D_ODT<1>")
		)
		(pad "92" smd rect
			(at 0 82.449924 90)
			(size 1.8034 0.508)
			(layers "F.Cu" "F.Mask" "F.Paste")
			(net "PVDDQ_DEF")
		)
		(pad "93" smd rect
			(at 0 83.300062 90)
			(size 1.8034 0.508)
			(layers "F.Cu" "F.Mask" "F.Paste")
			(net "M_D_CS_N<2>")
		)
		(pad "94" smd rect
			(at 0 84.149946 90)
			(size 1.8034 0.508)
			(layers "F.Cu" "F.Mask" "F.Paste")
			(net "GND")
		)
		(pad "95" smd rect
			(at 0 85.000084 90)
			(size 1.8034 0.508)
			(layers "F.Cu" "F.Mask" "F.Paste")
			(net "M_D_DQ<37>")
		)
		(pad "96" smd rect
			(at 0 85.849968 90)
			(size 1.8034 0.508)
			(layers "F.Cu" "F.Mask" "F.Paste")
			(net "GND")
		)
		(pad "97" smd rect
			(at 0 86.700106 90)
			(size 1.8034 0.508)
			(layers "F.Cu" "F.Mask" "F.Paste")
			(net "M_D_DQ<33>")
		)
		(pad "98" smd rect
			(at 0 87.54999 90)
			(size 1.8034 0.508)
			(layers "F.Cu" "F.Mask" "F.Paste")
			(net "GND")
		)
		(pad "99" smd rect
			(at 0 88.399874 90)
			(size 1.8034 0.508)
			(layers "F.Cu" "F.Mask" "F.Paste")
			(net "M_D_DQS_DP<13>")
		)
		(pad "100" smd rect
			(at 0 89.250012 90)
			(size 1.8034 0.508)
			(layers "F.Cu" "F.Mask" "F.Paste")
			(net "M_D_DQS_DN<13>")
		)
		(pad "101" smd rect
			(at 0 90.099896 90)
			(size 1.8034 0.508)
			(layers "F.Cu" "F.Mask" "F.Paste")
			(net "GND")
		)
		(pad "102" smd rect
			(at 0 90.950034 90)
			(size 1.8034 0.508)
			(layers "F.Cu" "F.Mask" "F.Paste")
			(net "M_D_DQ<39>")
		)
		(pad "103" smd rect
			(at 0 91.799918 90)
			(size 1.8034 0.508)
			(layers "F.Cu" "F.Mask" "F.Paste")
			(net "GND")
		)
		(pad "104" smd rect
			(at 0 92.650056 90)
			(size 1.8034 0.508)
			(layers "F.Cu" "F.Mask" "F.Paste")
			(net "M_D_DQ<35>")
		)
		(pad "105" smd rect
			(at 0 93.49994 90)
			(size 1.8034 0.508)
			(layers "F.Cu" "F.Mask" "F.Paste")
			(net "GND")
		)
		(pad "106" smd rect
			(at 0 94.350078 90)
			(size 1.8034 0.508)
			(layers "F.Cu" "F.Mask" "F.Paste")
			(net "M_D_DQ<45>")
		)
		(pad "107" smd rect
			(at 0 95.199962 90)
			(size 1.8034 0.508)
			(layers "F.Cu" "F.Mask" "F.Paste")
			(net "GND")
		)
		(pad "108" smd rect
			(at 0 96.0501 90)
			(size 1.8034 0.508)
			(layers "F.Cu" "F.Mask" "F.Paste")
			(net "M_D_DQ<41>")
		)
		(pad "109" smd rect
			(at 0 96.899984 90)
			(size 1.8034 0.508)
			(layers "F.Cu" "F.Mask" "F.Paste")
			(net "GND")
		)
		(pad "110" smd rect
			(at 0 97.750122 90)
			(size 1.8034 0.508)
			(layers "F.Cu" "F.Mask" "F.Paste")
			(net "M_D_DQS_DP<14>")
		)
		(pad "111" smd rect
			(at 0 98.600006 90)
			(size 1.8034 0.508)
			(layers "F.Cu" "F.Mask" "F.Paste")
			(net "M_D_DQS_DN<14>")
		)
		(pad "112" smd rect
			(at 0 99.44989 90)
			(size 1.8034 0.508)
			(layers "F.Cu" "F.Mask" "F.Paste")
			(net "GND")
		)
		(pad "113" smd rect
			(at 0 100.300028 90)
			(size 1.8034 0.508)
			(layers "F.Cu" "F.Mask" "F.Paste")
			(net "M_D_DQ<47>")
		)
		(pad "114" smd rect
			(at 0 101.149912 90)
			(size 1.8034 0.508)
			(layers "F.Cu" "F.Mask" "F.Paste")
			(net "GND")
		)
		(pad "115" smd rect
			(at 0 102.00005 90)
			(size 1.8034 0.508)
			(layers "F.Cu" "F.Mask" "F.Paste")
			(net "M_D_DQ<43>")
		)
		(pad "116" smd rect
			(at 0 102.849934 90)
			(size 1.8034 0.508)
			(layers "F.Cu" "F.Mask" "F.Paste")
			(net "GND")
		)
		(pad "117" smd rect
			(at 0 103.700072 90)
			(size 1.8034 0.508)
			(layers "F.Cu" "F.Mask" "F.Paste")
			(net "M_D_DQ<53>")
		)
		(pad "118" smd rect
			(at 0 104.549956 90)
			(size 1.8034 0.508)
			(layers "F.Cu" "F.Mask" "F.Paste")
			(net "GND")
		)
		(pad "119" smd rect
			(at 0 105.400094 90)
			(size 1.8034 0.508)
			(layers "F.Cu" "F.Mask" "F.Paste")
			(net "M_D_DQ<49>")
		)
		(pad "120" smd rect
			(at 0 106.249978 90)
			(size 1.8034 0.508)
			(layers "F.Cu" "F.Mask" "F.Paste")
			(net "GND")
		)
	)
)
